(kicad_pcb
	(version 20260206)
	(generator "pcbnew")
	(generator_version "10.0")
	(general
		(thickness 1.6)
		(legacy_teardrops no)
	)
	(paper "A4")
	(title_block
		(title "12092022_DA0F0TFB6D0_F0T_FAN_BOARD_MP5048_D_brd_v02_OCP.brd")
		(comment 1 "Grand Teton / footprints 698-703 of 924")
	)
	(layers
		(0 "F.Cu" signal "TOP")
		(4 "In1.Cu" signal "GND")
		(6 "In2.Cu" signal "IN1")
		(8 "In3.Cu" signal "IN2")
		(10 "In4.Cu" signal "GND1")
		(2 "B.Cu" signal "BOTTOM")
		(9 "F.Adhes" user "F.Adhesive")
		(11 "B.Adhes" user "B.Adhesive")
		(13 "F.Paste" user "Package Geometry/Pastemask Top")
		(15 "B.Paste" user "Package Geometry/Pastemask Bottom")
		(5 "F.SilkS" user "Ref Des/Silkscreen Top")
		(7 "B.SilkS" user "Ref Des/Silkscreen Bottom")
		(1 "F.Mask" user "Board Geometry/Soldermask Top")
		(3 "B.Mask" user "Board Geometry/Soldermask Bottom")
		(17 "Dwgs.User" user "User.Drawings")
		(19 "Cmts.User" user "User.Comments")
		(21 "Eco1.User" user "User.Eco1")
		(23 "Eco2.User" user "User.Eco2")
		(25 "Edge.Cuts" user "Board Geometry/Outline")
		(27 "Margin" user)
		(31 "F.CrtYd" user "Package Geometry/Place Bound Top")
		(29 "B.CrtYd" user "Package Geometry/Place Bound Bottom")
		(35 "F.Fab" user "Ref Des/Assembly Top")
		(33 "B.Fab" user "Ref Des/Assembly Bottom")
	)
	(footprint ""
		(layer "F.Cu")
		(at 45.466 -98.806 90)
		(property "Reference" "R5652"
			(at 0 0 90)
			(layer "F.SilkS")
			(hide yes)
			(effects
				(font
					(size 1.27 1.27)
				)
			)
		)
		(property "Value" ""
			(at 0 0 90)
			(layer "F.Fab")
			(effects
				(font
					(size 1.27 1.27)
				)
			)
		)
		(duplicate_pad_numbers_are_jumpers no)
		(fp_line
			(start 0.7874 -0.4064)
			(end 0.7874 0.4064)
			(stroke
				(width 0.1524)
				(type default)
			)
			(layer "F.SilkS")
		)
		(fp_line
			(start -0.7874 -0.4064)
			(end 0.7874 -0.4064)
			(stroke
				(width 0.1524)
				(type default)
			)
			(layer "F.SilkS")
		)
		(fp_line
			(start 0.7874 0.4064)
			(end -0.7874 0.4064)
			(stroke
				(width 0.1524)
				(type default)
			)
			(layer "F.SilkS")
		)
		(fp_line
			(start -0.7874 0.4064)
			(end -0.7874 -0.4064)
			(stroke
				(width 0.1524)
				(type default)
			)
			(layer "F.SilkS")
		)
		(fp_line
			(start -0.12065 -0.305054)
			(end -0.12065 -0.2794)
			(stroke
				(width 0.1)
				(type default)
			)
			(layer "F.Fab")
		)
		(fp_line
			(start -0.67945 -0.305054)
			(end -0.12065 -0.305054)
			(stroke
				(width 0.1)
				(type default)
			)
			(layer "F.Fab")
		)
		(fp_line
			(start 0.67945 -0.3048)
			(end 0.67945 0.3048)
			(stroke
				(width 0.1)
				(type default)
			)
			(layer "F.Fab")
		)
		(fp_line
			(start 0.12065 -0.3048)
			(end 0.67945 -0.3048)
			(stroke
				(width 0.1)
				(type default)
			)
			(layer "F.Fab")
		)
		(fp_line
			(start 0.12065 -0.2794)
			(end 0.12065 -0.3048)
			(stroke
				(width 0.1)
				(type default)
			)
			(layer "F.Fab")
		)
		(fp_line
			(start -0.12065 -0.2794)
			(end 0.12065 -0.2794)
			(stroke
				(width 0.1)
				(type default)
			)
			(layer "F.Fab")
		)
		(fp_line
			(start 0.120396 0.2794)
			(end -0.12065 0.2794)
			(stroke
				(width 0.1)
				(type default)
			)
			(layer "F.Fab")
		)
		(fp_line
			(start -0.12065 0.2794)
			(end -0.12065 0.3048)
			(stroke
				(width 0.1)
				(type default)
			)
			(layer "F.Fab")
		)
		(fp_line
			(start 0.67945 0.3048)
			(end 0.120396 0.3048)
			(stroke
				(width 0.1)
				(type default)
			)
			(layer "F.Fab")
		)
		(fp_line
			(start 0.120396 0.3048)
			(end 0.120396 0.2794)
			(stroke
				(width 0.1)
				(type default)
			)
			(layer "F.Fab")
		)
		(fp_line
			(start -0.12065 0.3048)
			(end -0.67945 0.3048)
			(stroke
				(width 0.1)
				(type default)
			)
			(layer "F.Fab")
		)
		(fp_line
			(start -0.67945 0.3048)
			(end -0.67945 -0.305054)
			(stroke
				(width 0.1)
				(type default)
			)
			(layer "F.Fab")
		)
		(pad "1" smd rect
			(at -0.40005 0 270)
			(size 0.4572 0.508)
			(layers "F.Cu" "F.Mask" "F.Paste")
			(net "P12V_LED")
		)
		(pad "2" smd rect
			(at 0.40005 0 270)
			(size 0.4572 0.508)
			(layers "F.Cu" "F.Mask" "F.Paste")
			(net "U407_D1")
		)
	)
	(footprint ""
		(layer "F.Cu")
		(at 37.338 -201.041)
		(property "Reference" "D270"
			(at 1.905 0.02667 0)
			(unlocked yes)
			(layer "F.SilkS")
			(effects
				(font
					(size 0.7874 0.5842)
					(thickness 0.1524)
				)
				(justify left)
			)
		)
		(property "Value" ""
			(at 0 0 0)
			(layer "F.Fab")
			(effects
				(font
					(size 1.27 1.27)
				)
			)
		)
		(duplicate_pad_numbers_are_jumpers no)
		(fp_line
			(start -0.854964 -0.450088)
			(end -0.854964 0.450088)
			(stroke
				(width 0.1524)
				(type default)
			)
			(layer "F.SilkS")
		)
		(fp_line
			(start -0.854964 0.450088)
			(end 0.925068 0.450088)
			(stroke
				(width 0.1524)
				(type default)
			)
			(layer "F.SilkS")
		)
		(fp_line
			(start 0.845058 0.4064)
			(end 0.845058 -0.381)
			(stroke
				(width 0.1524)
				(type default)
			)
			(layer "F.SilkS")
		)
		(fp_line
			(start 0.870458 -0.2794)
			(end 0.845058 0.4064)
			(stroke
				(width 0.1524)
				(type default)
			)
			(layer "F.SilkS")
		)
		(fp_line
			(start 0.94488 -0.450088)
			(end -0.854964 -0.450088)
			(stroke
				(width 0.1524)
				(type default)
			)
			(layer "F.SilkS")
		)
		(fp_line
			(start 0.94488 0.450088)
			(end 0.94488 -0.450088)
			(stroke
				(width 0.1524)
				(type default)
			)
			(layer "F.SilkS")
		)
		(fp_line
			(start -0.54991 -0.350012)
			(end -0.54991 0.350012)
			(stroke
				(width 0.1)
				(type default)
			)
			(layer "F.Fab")
		)
		(fp_line
			(start -0.54991 0.350012)
			(end 0.54991 0.350012)
			(stroke
				(width 0.1)
				(type default)
			)
			(layer "F.Fab")
		)
		(fp_line
			(start 0.54991 -0.350012)
			(end -0.54991 -0.350012)
			(stroke
				(width 0.1)
				(type default)
			)
			(layer "F.Fab")
		)
		(fp_line
			(start 0.54991 0.350012)
			(end 0.54991 -0.350012)
			(stroke
				(width 0.1)
				(type default)
			)
			(layer "F.Fab")
		)
		(fp_text user "+"
			(at -0.635 0.22225 180)
			(unlocked yes)
			(layer "F.SilkS")
			(effects
				(font
					(size 1.905 1.4224)
					(thickness 0.1524)
				)
				(justify left)
			)
		)
		(fp_text user "-"
			(at 2.159 0.22225 180)
			(unlocked yes)
			(layer "F.SilkS")
			(effects
				(font
					(size 1.905 1.4224)
					(thickness 0.1524)
				)
				(justify left)
			)
		)
		(fp_text user "+"
			(at -0.808228 0.239014 180)
			(unlocked yes)
			(layer "F.Fab")
			(effects
				(font
					(size 1.905 1.4224)
					(thickness 0.1524)
				)
				(justify left)
			)
		)
		(fp_text user "-"
			(at 2.48539 0.239014 180)
			(unlocked yes)
			(layer "F.Fab")
			(effects
				(font
					(size 1.905 1.4224)
					(thickness 0.1524)
				)
				(justify left)
			)
		)
		(pad "A" smd rect
			(at -0.424942 0)
			(size 0.5588 0.6096)
			(layers "F.Cu" "F.Mask" "F.Paste")
			(net "GND")
		)
		(pad "C" smd rect
			(at 0.424942 0 180)
			(size 0.5588 0.6096)
			(layers "F.Cu" "F.Mask" "F.Paste")
			(net "FAN_1_OK_R_LED_N")
		)
	)
	(footprint ""
		(layer "F.Cu")
		(at 15.621 -166.4716)
		(property "Reference" "C56"
			(at 0 0 0)
			(layer "F.SilkS")
			(hide yes)
			(effects
				(font
					(size 1.27 1.27)
				)
			)
		)
		(property "Value" ""
			(at 0 0 0)
			(layer "F.Fab")
			(effects
				(font
					(size 1.27 1.27)
				)
			)
		)
		(duplicate_pad_numbers_are_jumpers no)
		(fp_line
			(start -0.7874 -0.4064)
			(end 0.7874 -0.4064)
			(stroke
				(width 0.1524)
				(type default)
			)
			(layer "F.SilkS")
		)
		(fp_line
			(start -0.7874 0.4064)
			(end -0.7874 -0.4064)
			(stroke
				(width 0.1524)
				(type default)
			)
			(layer "F.SilkS")
		)
		(fp_line
			(start 0.7874 -0.4064)
			(end 0.7874 0.4064)
			(stroke
				(width 0.1524)
				(type default)
			)
			(layer "F.SilkS")
		)
		(fp_line
			(start 0.7874 0.4064)
			(end -0.7874 0.4064)
			(stroke
				(width 0.1524)
				(type default)
			)
			(layer "F.SilkS")
		)
		(fp_line
			(start -0.67945 -0.305054)
			(end -0.12065 -0.305054)
			(stroke
				(width 0.1)
				(type default)
			)
			(layer "F.Fab")
		)
		(fp_line
			(start -0.67945 0.3048)
			(end -0.67945 -0.305054)
			(stroke
				(width 0.1)
				(type default)
			)
			(layer "F.Fab")
		)
		(fp_line
			(start -0.12065 -0.305054)
			(end -0.12065 -0.2794)
			(stroke
				(width 0.1)
				(type default)
			)
			(layer "F.Fab")
		)
		(fp_line
			(start -0.12065 -0.2794)
			(end 0.12065 -0.2794)
			(stroke
				(width 0.1)
				(type default)
			)
			(layer "F.Fab")
		)
		(fp_line
			(start -0.12065 0.2794)
			(end -0.12065 0.3048)
			(stroke
				(width 0.1)
				(type default)
			)
			(layer "F.Fab")
		)
		(fp_line
			(start -0.12065 0.3048)
			(end -0.67945 0.3048)
			(stroke
				(width 0.1)
				(type default)
			)
			(layer "F.Fab")
		)
		(fp_line
			(start 0.120396 0.2794)
			(end -0.12065 0.2794)
			(stroke
				(width 0.1)
				(type default)
			)
			(layer "F.Fab")
		)
		(fp_line
			(start 0.120396 0.3048)
			(end 0.120396 0.2794)
			(stroke
				(width 0.1)
				(type default)
			)
			(layer "F.Fab")
		)
		(fp_line
			(start 0.12065 -0.3048)
			(end 0.67945 -0.3048)
			(stroke
				(width 0.1)
				(type default)
			)
			(layer "F.Fab")
		)
		(fp_line
			(start 0.12065 -0.2794)
			(end 0.12065 -0.3048)
			(stroke
				(width 0.1)
				(type default)
			)
			(layer "F.Fab")
		)
		(fp_line
			(start 0.67945 -0.3048)
			(end 0.67945 0.3048)
			(stroke
				(width 0.1)
				(type default)
			)
			(layer "F.Fab")
		)
		(fp_line
			(start 0.67945 0.3048)
			(end 0.120396 0.3048)
			(stroke
				(width 0.1)
				(type default)
			)
			(layer "F.Fab")
		)
		(pad "1" smd circle
			(at -0.40005 0)
			(size 0 0)
			(layers "F.Cu" "F.Mask" "F.Paste")
			(net "FAN_2_PRESENT_N")
		)
		(pad "2" smd circle
			(at 0.40005 0)
			(size 0 0)
			(layers "F.Cu" "F.Mask" "F.Paste")
			(net "GND")
		)
	)
	(footprint ""
		(layer "F.Cu")
		(at 37.846 -128.778 180)
		(property "Reference" "R5604"
			(at 0 0 180)
			(layer "F.SilkS")
			(hide yes)
			(effects
				(font
					(size 1.27 1.27)
				)
			)
		)
		(property "Value" ""
			(at 0 0 180)
			(layer "F.Fab")
			(effects
				(font
					(size 1.27 1.27)
				)
			)
		)
		(duplicate_pad_numbers_are_jumpers no)
		(fp_line
			(start 0.7874 0.4064)
			(end -0.7874 0.4064)
			(stroke
				(width 0.1524)
				(type default)
			)
			(layer "F.SilkS")
		)
		(fp_line
			(start 0.7874 -0.4064)
			(end 0.7874 0.4064)
			(stroke
				(width 0.1524)
				(type default)
			)
			(layer "F.SilkS")
		)
		(fp_line
			(start -0.7874 0.4064)
			(end -0.7874 -0.4064)
			(stroke
				(width 0.1524)
				(type default)
			)
			(layer "F.SilkS")
		)
		(fp_line
			(start -0.7874 -0.4064)
			(end 0.7874 -0.4064)
			(stroke
				(width 0.1524)
				(type default)
			)
			(layer "F.SilkS")
		)
		(fp_line
			(start 0.67945 0.3048)
			(end 0.120396 0.3048)
			(stroke
				(width 0.1)
				(type default)
			)
			(layer "F.Fab")
		)
		(fp_line
			(start 0.67945 -0.3048)
			(end 0.67945 0.3048)
			(stroke
				(width 0.1)
				(type default)
			)
			(layer "F.Fab")
		)
		(fp_line
			(start 0.12065 -0.2794)
			(end 0.12065 -0.3048)
			(stroke
				(width 0.1)
				(type default)
			)
			(layer "F.Fab")
		)
		(fp_line
			(start 0.12065 -0.3048)
			(end 0.67945 -0.3048)
			(stroke
				(width 0.1)
				(type default)
			)
			(layer "F.Fab")
		)
		(fp_line
			(start 0.120396 0.3048)
			(end 0.120396 0.2794)
			(stroke
				(width 0.1)
				(type default)
			)
			(layer "F.Fab")
		)
		(fp_line
			(start 0.120396 0.2794)
			(end -0.12065 0.2794)
			(stroke
				(width 0.1)
				(type default)
			)
			(layer "F.Fab")
		)
		(fp_line
			(start -0.12065 0.3048)
			(end -0.67945 0.3048)
			(stroke
				(width 0.1)
				(type default)
			)
			(layer "F.Fab")
		)
		(fp_line
			(start -0.12065 0.2794)
			(end -0.12065 0.3048)
			(stroke
				(width 0.1)
				(type default)
			)
			(layer "F.Fab")
		)
		(fp_line
			(start -0.12065 -0.2794)
			(end 0.12065 -0.2794)
			(stroke
				(width 0.1)
				(type default)
			)
			(layer "F.Fab")
		)
		(fp_line
			(start -0.12065 -0.305054)
			(end -0.12065 -0.2794)
			(stroke
				(width 0.1)
				(type default)
			)
			(layer "F.Fab")
		)
		(fp_line
			(start -0.67945 0.3048)
			(end -0.67945 -0.305054)
			(stroke
				(width 0.1)
				(type default)
			)
			(layer "F.Fab")
		)
		(fp_line
			(start -0.67945 -0.305054)
			(end -0.12065 -0.305054)
			(stroke
				(width 0.1)
				(type default)
			)
			(layer "F.Fab")
		)
		(pad "1" smd rect
			(at -0.40005 0)
			(size 0.4572 0.508)
			(layers "F.Cu" "F.Mask" "F.Paste")
			(net "FAN_2_TACH_IL")
		)
		(pad "2" smd rect
			(at 0.40005 0)
			(size 0.4572 0.508)
			(layers "F.Cu" "F.Mask" "F.Paste")
			(net "FAN_2_TACH_IL_R1")
		)
	)
	(footprint ""
		(layer "F.Cu")
		(at 35.306 -304.165 180)
		(property "Reference" "C2020"
			(at 0 0 180)
			(layer "F.SilkS")
			(hide yes)
			(effects
				(font
					(size 1.27 1.27)
				)
			)
		)
		(property "Value" ""
			(at 0 0 180)
			(layer "F.Fab")
			(effects
				(font
					(size 1.27 1.27)
				)
			)
		)
		(duplicate_pad_numbers_are_jumpers no)
		(fp_line
			(start 0.7874 0.4064)
			(end -0.7874 0.4064)
			(stroke
				(width 0.1524)
				(type default)
			)
			(layer "F.SilkS")
		)
		(fp_line
			(start 0.7874 -0.4064)
			(end 0.7874 0.4064)
			(stroke
				(width 0.1524)
				(type default)
			)
			(layer "F.SilkS")
		)
		(fp_line
			(start -0.7874 0.4064)
			(end -0.7874 -0.4064)
			(stroke
				(width 0.1524)
				(type default)
			)
			(layer "F.SilkS")
		)
		(fp_line
			(start -0.7874 -0.4064)
			(end 0.7874 -0.4064)
			(stroke
				(width 0.1524)
				(type default)
			)
			(layer "F.SilkS")
		)
		(fp_line
			(start 0.67945 0.3048)
			(end 0.120396 0.3048)
			(stroke
				(width 0.1)
				(type default)
			)
			(layer "F.Fab")
		)
		(fp_line
			(start 0.67945 -0.3048)
			(end 0.67945 0.3048)
			(stroke
				(width 0.1)
				(type default)
			)
			(layer "F.Fab")
		)
		(fp_line
			(start 0.12065 -0.2794)
			(end 0.12065 -0.3048)
			(stroke
				(width 0.1)
				(type default)
			)
			(layer "F.Fab")
		)
		(fp_line
			(start 0.12065 -0.3048)
			(end 0.67945 -0.3048)
			(stroke
				(width 0.1)
				(type default)
			)
			(layer "F.Fab")
		)
		(fp_line
			(start 0.120396 0.3048)
			(end 0.120396 0.2794)
			(stroke
				(width 0.1)
				(type default)
			)
			(layer "F.Fab")
		)
		(fp_line
			(start 0.120396 0.2794)
			(end -0.12065 0.2794)
			(stroke
				(width 0.1)
				(type default)
			)
			(layer "F.Fab")
		)
		(fp_line
			(start -0.12065 0.3048)
			(end -0.67945 0.3048)
			(stroke
				(width 0.1)
				(type default)
			)
			(layer "F.Fab")
		)
		(fp_line
			(start -0.12065 0.2794)
			(end -0.12065 0.3048)
			(stroke
				(width 0.1)
				(type default)
			)
			(layer "F.Fab")
		)
		(fp_line
			(start -0.12065 -0.2794)
			(end 0.12065 -0.2794)
			(stroke
				(width 0.1)
				(type default)
			)
			(layer "F.Fab")
		)
		(fp_line
			(start -0.12065 -0.305054)
			(end -0.12065 -0.2794)
			(stroke
				(width 0.1)
				(type default)
			)
			(layer "F.Fab")
		)
		(fp_line
			(start -0.67945 0.3048)
			(end -0.67945 -0.305054)
			(stroke
				(width 0.1)
				(type default)
			)
			(layer "F.Fab")
		)
		(fp_line
			(start -0.67945 -0.305054)
			(end -0.12065 -0.305054)
			(stroke
				(width 0.1)
				(type default)
			)
			(layer "F.Fab")
		)
		(pad "1" smd circle
			(at -0.40005 0 180)
			(size 0 0)
			(layers "F.Cu" "F.Mask" "F.Paste")
			(net "FAN_0_PWM_OL_R")
		)
		(pad "2" smd circle
			(at 0.40005 0 180)
			(size 0 0)
			(layers "F.Cu" "F.Mask" "F.Paste")
			(net "GND")
		)
	)
	(footprint ""
		(layer "F.Cu")
		(at 5.461 -186.436)
		(property "Reference" "R310"
			(at 0 0 0)
			(layer "F.SilkS")
			(hide yes)
			(effects
				(font
					(size 1.27 1.27)
				)
			)
		)
		(property "Value" ""
			(at 0 0 0)
			(layer "F.Fab")
			(effects
				(font
					(size 1.27 1.27)
				)
			)
		)
		(duplicate_pad_numbers_are_jumpers no)
		(fp_line
			(start -0.7874 -0.4064)
			(end 0.7874 -0.4064)
			(stroke
				(width 0.1524)
				(type default)
			)
			(layer "F.SilkS")
		)
		(fp_line
			(start -0.7874 0.4064)
			(end -0.7874 -0.4064)
			(stroke
				(width 0.1524)
				(type default)
			)
			(layer "F.SilkS")
		)
		(fp_line
			(start 0.7874 -0.4064)
			(end 0.7874 0.4064)
			(stroke
				(width 0.1524)
				(type default)
			)
			(layer "F.SilkS")
		)
		(fp_line
			(start 0.7874 0.4064)
			(end -0.7874 0.4064)
			(stroke
				(width 0.1524)
				(type default)
			)
			(layer "F.SilkS")
		)
		(fp_line
			(start -0.67945 -0.305054)
			(end -0.12065 -0.305054)
			(stroke
				(width 0.1)
				(type default)
			)
			(layer "F.Fab")
		)
		(fp_line
			(start -0.67945 0.3048)
			(end -0.67945 -0.305054)
			(stroke
				(width 0.1)
				(type default)
			)
			(layer "F.Fab")
		)
		(fp_line
			(start -0.12065 -0.305054)
			(end -0.12065 -0.2794)
			(stroke
				(width 0.1)
				(type default)
			)
			(layer "F.Fab")
		)
		(fp_line
			(start -0.12065 -0.2794)
			(end 0.12065 -0.2794)
			(stroke
				(width 0.1)
				(type default)
			)
			(layer "F.Fab")
		)
		(fp_line
			(start -0.12065 0.2794)
			(end -0.12065 0.3048)
			(stroke
				(width 0.1)
				(type default)
			)
			(layer "F.Fab")
		)
		(fp_line
			(start -0.12065 0.3048)
			(end -0.67945 0.3048)
			(stroke
				(width 0.1)
				(type default)
			)
			(layer "F.Fab")
		)
		(fp_line
			(start 0.120396 0.2794)
			(end -0.12065 0.2794)
			(stroke
				(width 0.1)
				(type default)
			)
			(layer "F.Fab")
		)
		(fp_line
			(start 0.120396 0.3048)
			(end 0.120396 0.2794)
			(stroke
				(width 0.1)
				(type default)
			)
			(layer "F.Fab")
		)
		(fp_line
			(start 0.12065 -0.3048)
			(end 0.67945 -0.3048)
			(stroke
				(width 0.1)
				(type default)
			)
			(layer "F.Fab")
		)
		(fp_line
			(start 0.12065 -0.2794)
			(end 0.12065 -0.3048)
			(stroke
				(width 0.1)
				(type default)
			)
			(layer "F.Fab")
		)
		(fp_line
			(start 0.67945 -0.3048)
			(end 0.67945 0.3048)
			(stroke
				(width 0.1)
				(type default)
			)
			(layer "F.Fab")
		)
		(fp_line
			(start 0.67945 0.3048)
			(end 0.120396 0.3048)
			(stroke
				(width 0.1)
				(type default)
			)
			(layer "F.Fab")
		)
		(pad "1" smd circle
			(at -0.40005 0)
			(size 0 0)
			(layers "F.Cu" "F.Mask" "F.Paste")
			(net "P3V3_AUX")
		)
		(pad "2" smd circle
			(at 0.40005 0)
			(size 0 0)
			(layers "F.Cu" "F.Mask" "F.Paste")
			(net "FRU_ADDR2")
		)
	)
)
